# S9S_MB_2U (Grand Teton) — schematic netlist excerpt (pin names and nets, part order shuffled) for the footprints in the layout excerpt that follows; sources: Cadence DE-HDL packaged netlist, KiCad conversion of 03242023_DA0F0TMBIJ0_F0T_Motherboard_J_brd_V01_OCP.brd

J12  SCONN288_ADR50017P087CC  SCONN288_ADR50017-P087CC IO  pkg DDR288S_1-1VXB  page 93
  VIN_BULK0  = P12V_S3_AUX_CPU0_NVDIMM
  RFU0  = TP_CHF_CPU0_DIMM2_FRU_0
  VIN_MGMT  = P3V3_AUX
  HSCL  = I3C_SPD_DDREFGH_CPU0_LVC1_SCL_3
  HSDA  = I3C_SPD_DDREFGH_CPU0_LVC1_SDA
  VSS0  = GND
  DQ0_A  = M_F_CPU0_SA_DQ<0>
  VSS1  = GND
  DQ1_A  = M_F_CPU0_SA_DQ<1>
  VSS2  = GND
  DQS0_A_T  = M_F_CPU0_SA_DQS_DP<0>
  DQS0_A_C  = M_F_CPU0_SA_DQS_DN<0>
  VSS3  = GND
  DQ4_A  = M_F_CPU0_SA_DQ<4>
  VSS4  = GND
  DQ5_A  = M_F_CPU0_SA_DQ<5>
  VSS5  = GND
  DQ8_A  = M_F_CPU0_SA_DQ<8>
  VSS6  = GND
  DQ9_A  = M_F_CPU0_SA_DQ<9>
  VSS7  = GND
  DQS1_A_T  = M_F_CPU0_SA_DQS_DP<1>
  DQS1_A_C  = M_F_CPU0_SA_DQS_DN<1>
  VSS8  = GND
  DQ12_A  = M_F_CPU0_SA_DQ<12>
  VSS9  = GND
  DQ13_A  = M_F_CPU0_SA_DQ<13>
  VSS10  = GND
  DQ16_A  = M_F_CPU0_SA_DQ<16>
  VSS11  = GND
  DQ17_A  = M_F_CPU0_SA_DQ<17>
  VSS12  = GND
  DQS2_A_T  = M_F_CPU0_SA_DQS_DP<2>
  DQS2_A_C  = M_F_CPU0_SA_DQS_DN<2>
  VSS13  = GND
  DQ20_A  = M_F_CPU0_SA_DQ<20>
  VSS14  = GND
  DQ21_A  = M_F_CPU0_SA_DQ<21>
  VSS15  = GND
  DQ24_A  = M_F_CPU0_SA_DQ<24>
  VSS16  = GND
  DQ25_A  = M_F_CPU0_SA_DQ<25>
  VSS17  = GND
  DQS3_A_T  = M_F_CPU0_SA_DQS_DP<3>
  DQS3_A_C  = M_F_CPU0_SA_DQS_DN<3>
  VSS18  = GND
  DQ28_A  = M_F_CPU0_SA_DQ<28>
  VSS19  = GND
  DQ29_A  = M_F_CPU0_SA_DQ<29>
  VSS20  = GND
  CB0_A  = M_F_CPU0_SA_CB<0>
  VSS21  = GND
  CB1_A  = M_F_CPU0_SA_CB<1>
  VSS22  = GND
  DQS4_A_T  = M_F_CPU0_SA_DQS_DP<4>
  DQS4_A_C  = M_F_CPU0_SA_DQS_DN<4>
  VSS23  = GND
  CB4_A  = M_F_CPU0_SA_CB<4>
  VSS24  = GND
  CB5_A  = M_F_CPU0_SA_CB<5>
  VSS25  = GND
  ALERT_N  = M_F_CPU0_ALERT_N
  VSS26  = GND
  CS0_A_N  = M_F_CPU0_SA_CS_N<2>
  VSS27  = GND
  CA0_A  = M_F_CPU0_SA_CA<0>
  VSS28  = GND
  CA2_A  = M_F_CPU0_SA_CA<2>
  VSS29  = GND
  CA4_A  = M_F_CPU0_SA_CA<4>
  VSS30  = GND
  CA6_A  = M_F_CPU0_SA_CA<6>
  VSS31  = GND
  PAR_A  = M_F_CPU0_SA_PAR
  VSS32  = GND
  CA0_B  = M_F_CPU0_SB_CA<0>
  VSS33  = GND
  CA2_B  = M_F_CPU0_SB_CA<2>
  VSS34  = GND
  CA4_B  = M_F_CPU0_SB_CA<4>
  VSS35  = GND
  CA6_B  = M_F_CPU0_SB_CA<6>
  VSS36  = GND
  CS0_B_N  = M_F_CPU0_SB_CS_N<2>
  VSS37  = GND
  \lbd||rsp_a_n\  = M_F_CPU0_SA_RSP<1>
  \lbs||rsp_b_n\  = M_F_CPU0_SB_RSP<1>
  VSS38  = GND
  CB4_B  = M_F_CPU0_SB_CB<4>
  VSS39  = GND
  CB5_B  = M_F_CPU0_SB_CB<5>
  VSS40  = GND
  \dqs9_b_t||tdqs9_b_t||dbi4_b_n\  = M_F_CPU0_SB_DQS_DP<9>
  \dqs9_b_c||tdqs9_b_c\  = M_F_CPU0_SB_DQS_DN<9>
  VSS41  = GND
  CB0_B  = M_F_CPU0_SB_CB<0>
  VSS42  = GND
  CB1_B  = M_F_CPU0_SB_CB<1>
  VSS43  = GND
  DQ0_B  = M_F_CPU0_SB_DQ<0>
  VSS44  = GND
  DQ1_B  = M_F_CPU0_SB_DQ<1>
  VSS45  = GND
  DQS0_B_T  = M_F_CPU0_SB_DQS_DP<0>
  DQS0_B_C  = M_F_CPU0_SB_DQS_DN<0>
  VSS46  = GND
  DQ4_B  = M_F_CPU0_SB_DQ<4>
  VSS47  = GND
  DQ5_B  = M_F_CPU0_SB_DQ<5>
  VSS48  = GND
  DQ8_B  = M_F_CPU0_SB_DQ<8>
  VSS49  = GND
  DQ9_B  = M_F_CPU0_SB_DQ<9>
  VSS50  = GND
  DQS1_B_T  = M_F_CPU0_SB_DQS_DP<1>
  DQS1_B_C  = M_F_CPU0_SB_DQS_DN<1>
  VSS51  = GND
  DQ12_B  = M_F_CPU0_SB_DQ<12>
  VSS52  = GND
  DQ13_B  = M_F_CPU0_SB_DQ<13>
  VSS53  = GND
  DQ16_B  = M_F_CPU0_SB_DQ<16>
  VSS54  = GND
  DQ17_B  = M_F_CPU0_SB_DQ<17>
  VSS55  = GND
  DQS2_B_T  = M_F_CPU0_SB_DQS_DP<2>
  DQS2_B_C  = M_F_CPU0_SB_DQS_DN<2>
  VSS56  = GND
  DQ20_B  = M_F_CPU0_SB_DQ<20>
  VSS57  = GND
  DQ21_B  = M_F_CPU0_SB_DQ<21>
  VSS58  = GND
  DQ24_B  = M_F_CPU0_SB_DQ<24>
  VSS59  = GND
  DQ25_B  = M_F_CPU0_SB_DQ<25>
  VSS60  = GND
  DQS3_B_T  = M_F_CPU0_SB_DQS_DP<3>
  DQS3_B_C  = M_F_CPU0_SB_DQS_DN<3>
  VSS61  = GND
  DQ28_B  = M_F_CPU0_SB_DQ<28>
  VSS62  = GND
  DQ29_B  = M_F_CPU0_SB_DQ<29>
  VSS63  = GND
  RFU1  = TP_CHF_CPU0_DIMM2_FRU_1
  VIN_BULK1  = P12V_S3_AUX_CPU0_NVDIMM
  VIN_BULK2  = P12V_S3_AUX_CPU0_NVDIMM
  \pwr_good||fail_n\  = PWRGD_CHF_CPU0_DIMM2
  HSA  = PD_CHF_CPU0_DIMM2_SAA
  RFU2  = TP_CHF_CPU0_DIMM2_FRU_2
  RFU3  = TP_CHF_CPU0_DIMM2_FRU_3
  VSS64  = GND
  DQ2_A  = M_F_CPU0_SA_DQ<2>
  VSS65  = GND
  DQ3_A  = M_F_CPU0_SA_DQ<3>
  VSS66  = GND
  \dqs5_a_c||tdqs5_a_c||dqs5_a_t||tdqs5_a_t\  = M_F_CPU0_SA_DQS_DN<5>
  \dqs5_a_t||tdqs5_a_t\  = M_F_CPU0_SA_DQS_DP<5>
  VSS67  = GND
  DQ6_A  = M_F_CPU0_SA_DQ<6>
  VSS68  = GND
  DQ7_A  = M_F_CPU0_SA_DQ<7>
  VSS69  = GND
  DQ10_A  = M_F_CPU0_SA_DQ<10>
  VSS70  = GND
  DQ11_A  = M_F_CPU0_SA_DQ<11>
  VSS71  = GND
  \dqs6_a_c||tdqs6_a_c||dqs6_a_t||tdqs6_a_t\  = M_F_CPU0_SA_DQS_DN<6>
  \dqs6_a_t||tdqs6_a_t\  = M_F_CPU0_SA_DQS_DP<6>
  VSS72  = GND
  DQ14_A  = M_F_CPU0_SA_DQ<14>
  VSS73  = GND
  DQ15_A  = M_F_CPU0_SA_DQ<15>
  VSS74  = GND
  DQ18_A  = M_F_CPU0_SA_DQ<18>
  VSS75  = GND
  DQ19_A  = M_F_CPU0_SA_DQ<19>
  VSS76  = GND
  \dqs7_a_c||tdqs7_a_c\  = M_F_CPU0_SA_DQS_DN<7>
  \dqs7_a_t||tdqs7_a_t\  = M_F_CPU0_SA_DQS_DP<7>
  VSS77  = GND
  DQ22_A  = M_F_CPU0_SA_DQ<22>
  VSS78  = GND
  DQ23_A  = M_F_CPU0_SA_DQ<23>
  VSS79  = GND
  DQ26_A  = M_F_CPU0_SA_DQ<26>
  VSS80  = GND
  DQ27_A  = M_F_CPU0_SA_DQ<27>
  VSS81  = GND
  \dqs8_a_c||tdqs8_a_c\  = M_F_CPU0_SA_DQS_DN<8>
  \dqs8_a_t||tdqs8_a_t\  = M_F_CPU0_SA_DQS_DP<8>
  VSS82  = GND
  DQ30_A  = M_F_CPU0_SA_DQ<30>
  VSS83  = GND
  DQ31_A  = M_F_CPU0_SA_DQ<31>
  VSS84  = GND
  CB2_A  = M_F_CPU0_SA_CB<2>
  VSS85  = GND
  CB3_A  = M_F_CPU0_SA_CB<3>
  VSS86  = GND
  \dqs9_a_c||tdqs9_a_c\  = M_F_CPU0_SA_DQS_DN<9>
  \dqs9_a_t||tdqs9_a_t\  = M_F_CPU0_SA_DQS_DP<9>
  VSS87  = GND
  CB6_A  = M_F_CPU0_SA_CB<6>
  VSS88  = GND
  CB7_A  = M_F_CPU0_SA_CB<7>
  VSS89  = GND
  RESET_N  = RST_M_EF_CPU0_FPGA_N
  VSS90  = GND
  CS1_A_N  = M_F_CPU0_SA_CS_N<3>
  VSS91  = GND
  CA1_A  = M_F_CPU0_SA_CA<1>
  VSS92  = GND
  CA3_A  = M_F_CPU0_SA_CA<3>
  VSS93  = GND
  CA5_A  = M_F_CPU0_SA_CA<5>
  VSS94  = GND
  CK_T  = M_F_CPU0_CLK_DP<1>
  CK_C  = M_F_CPU0_CLK_DN<1>
  VSS95  = GND
  RFU4  = TP_CHF_CPU0_DIMM2_FRU_4
  CA1_B  = M_F_CPU0_SB_CA<1>
  VSS96  = GND
  CA3_B  = M_F_CPU0_SB_CA<3>
  VSS97  = GND
  CA5_B  = M_F_CPU0_SB_CA<5>
  VSS98  = GND
  PAR_B  = M_F_CPU0_SB_PAR
  VSS99  = GND
  CS1_B_N  = M_F_CPU0_SB_CS_N<3>
  VSS100  = GND
  RFU5  = TP_CHF_CPU0_DIMM2_FRU_5
  RFU6  = TP_CHF_CPU0_DIMM2_FRU_6
  VSS101  = GND
  CB6_B  = M_F_CPU0_SB_CB<6>
  VSS102  = GND
  CB7_B  = M_F_CPU0_SB_CB<7>
  VSS103  = GND
  DQS4_B_C  = M_F_CPU0_SB_DQS_DN<4>
  DQS4_B_T  = M_F_CPU0_SB_DQS_DP<4>
  VSS104  = GND
  CB2_B  = M_F_CPU0_SB_CB<2>
  VSS105  = GND
  CB3_B  = M_F_CPU0_SB_CB<3>
  VSS106  = GND
  DQ2_B  = M_F_CPU0_SB_DQ<2>
  VSS107  = GND
  DQ3_B  = M_F_CPU0_SB_DQ<3>
  VSS108  = GND
  \dqs5_b_c||tdqs5_b_c\  = M_F_CPU0_SB_DQS_DN<5>
  \dqs5_b_t||tdqs5_b_t\  = M_F_CPU0_SB_DQS_DP<5>
  VSS109  = GND
  DQ6_B  = M_F_CPU0_SB_DQ<6>
  VSS110  = GND
  DQ7_B  = M_F_CPU0_SB_DQ<7>
  VSS111  = GND
  DQ10_B  = M_F_CPU0_SB_DQ<10>
  VSS112  = GND
  DQ11_B  = M_F_CPU0_SB_DQ<11>
  VSS113  = GND
  \dqs6_b_c||tdqs6_b_c\  = M_F_CPU0_SB_DQS_DN<6>
  \dqs6_b_t||tdqs6_b_t\  = M_F_CPU0_SB_DQS_DP<6>
  VSS114  = GND
  DQ14_B  = M_F_CPU0_SB_DQ<14>
  VSS115  = GND
  DQ15_B  = M_F_CPU0_SB_DQ<15>
  VSS116  = GND
  DQ18_B  = M_F_CPU0_SB_DQ<18>
  VSS117  = GND
  DQ19_B  = M_F_CPU0_SB_DQ<19>
  VSS118  = GND
  \dqs7_b_c||tdqs7_b_c\  = M_F_CPU0_SB_DQS_DN<7>
  \dqs7_b_t||tdqs7_b_t\  = M_F_CPU0_SB_DQS_DP<7>
  VSS119  = GND
  DQ22_B  = M_F_CPU0_SB_DQ<22>
  VSS120  = GND
  DQ23_B  = M_F_CPU0_SB_DQ<23>
  VSS121  = GND
  DQ26_B  = M_F_CPU0_SB_DQ<26>
  VSS122  = GND
  DQ27_B  = M_F_CPU0_SB_DQ<27>
  VSS123  = GND
  \dqs8_b_c||tdqs8_b_c\  = M_F_CPU0_SB_DQS_DN<8>
  \dqs8_b_t||tdqs8_b_t\  = M_F_CPU0_SB_DQS_DP<8>
  VSS124  = GND
  DQ30_B  = M_F_CPU0_SB_DQ<30>
  VSS125  = GND
  DQ31_B  = M_F_CPU0_SB_DQ<31>
  VSS126  = GND
  G1  = GND
  G2  = GND
  G3  = GND

(kicad_pcb
	(version 20260206)
	(generator "pcbnew")
	(generator_version "10.0")
	(general
		(thickness 1.6)
		(legacy_teardrops no)
	)
	(paper "A4")
	(title_block
		(title "03242023_DA0F0TMBIJ0_F0T_Motherboard_J_brd_V01_OCP.brd")
		(comment 1 "Grand Teton / footprint 3198 of 6105 (J12), pads 1-45 of 291")
	)
	(layers
		(0 "F.Cu" signal "TOP")
		(4 "In1.Cu" signal "GND")
		(6 "In2.Cu" signal "IN1")
		(8 "In3.Cu" signal "GND1")
		(10 "In4.Cu" signal "IN2")
		(12 "In5.Cu" signal "GND2")
		(14 "In6.Cu" signal "IN3")
		(16 "In7.Cu" signal "GND3")
		(18 "In8.Cu" signal "VCC")
		(20 "In9.Cu" signal "VCC1")
		(22 "In10.Cu" signal "GND4")
		(24 "In11.Cu" signal "IN4")
		(26 "In12.Cu" signal "GND5")
		(28 "In13.Cu" signal "IN5")
		(30 "In14.Cu" signal "GND6")
		(32 "In15.Cu" signal "IN6")
		(34 "In16.Cu" signal "GND7")
		(2 "B.Cu" signal "BOTTOM")
		(9 "F.Adhes" user "F.Adhesive")
		(11 "B.Adhes" user "B.Adhesive")
		(13 "F.Paste" user "Package Geometry/Pastemask Top")
		(15 "B.Paste" user "Package Geometry/Pastemask Bottom")
		(5 "F.SilkS" user "Ref Des/Silkscreen Top")
		(7 "B.SilkS" user "Ref Des/Silkscreen Bottom")
		(1 "F.Mask" user "Board Geometry/Soldermask Top")
		(3 "B.Mask" user "Board Geometry/Soldermask Bottom")
		(17 "Dwgs.User" user "User.Drawings")
		(19 "Cmts.User" user "User.Comments")
		(21 "Eco1.User" user "User.Eco1")
		(23 "Eco2.User" user "User.Eco2")
		(25 "Edge.Cuts" user "Board Geometry/Outline")
		(27 "Margin" user)
		(31 "F.CrtYd" user "Package Geometry/Place Bound Top")
		(29 "B.CrtYd" user "Package Geometry/Place Bound Bottom")
		(35 "F.Fab" user "Ref Des/Assembly Top")
		(33 "B.Fab" user "Ref Des/Assembly Bottom")
	)
	(footprint ""
		(layer "F.Cu")
		(at 423.890948 -258.091686)
		(property "Reference" "J12"
			(at -3.683 -81.702148 0)
			(unlocked yes)
			(layer "F.SilkS")
			(effects
				(font
					(size 0.7874 0.5842)
					(thickness 0.1524)
				)
				(justify left)
			)
		)
		(property "Value" ""
			(at 0 0 0)
			(layer "F.Fab")
			(effects
				(font
					(size 1.27 1.27)
				)
			)
		)
		(duplicate_pad_numbers_are_jumpers no)
		(pad "1" smd rect
			(at -2.050034 -63.324994 270)
			(size 0.519938 1.4986)
			(layers "F.Cu" "F.Mask" "F.Paste")
			(net "P12V_S3_AUX_CPU0_NVDIMM")
		)
		(pad "2" smd rect
			(at -2.050034 -62.47511 270)
			(size 0.519938 1.4986)
			(layers "F.Cu" "F.Mask" "F.Paste")
			(net "TP_CHF_CPU0_DIMM2_FRU_0")
		)
		(pad "3" smd rect
			(at -2.050034 -61.624972 270)
			(size 0.519938 1.4986)
			(layers "F.Cu" "F.Mask" "F.Paste")
			(net "P3V3_AUX")
		)
		(pad "4" smd rect
			(at -2.050034 -60.775088 270)
			(size 0.519938 1.4986)
			(layers "F.Cu" "F.Mask" "F.Paste")
			(net "I3C_SPD_DDREFGH_CPU0_LVC1_SCL_3")
		)
		(pad "5" smd rect
			(at -2.050034 -59.92495 270)
			(size 0.519938 1.4986)
			(layers "F.Cu" "F.Mask" "F.Paste")
			(net "I3C_SPD_DDREFGH_CPU0_LVC1_SDA")
		)
		(pad "6" smd rect
			(at -2.050034 -59.075066 270)
			(size 0.519938 1.4986)
			(layers "F.Cu" "F.Mask" "F.Paste")
			(net "GND")
		)
		(pad "7" smd rect
			(at -2.050034 -58.224928 270)
			(size 0.519938 1.4986)
			(layers "F.Cu" "F.Mask" "F.Paste")
			(net "M_F_CPU0_SA_DQ<0>")
		)
		(pad "8" smd rect
			(at -2.050034 -57.375044 270)
			(size 0.519938 1.4986)
			(layers "F.Cu" "F.Mask" "F.Paste")
			(net "GND")
		)
		(pad "9" smd rect
			(at -2.050034 -56.524906 270)
			(size 0.519938 1.4986)
			(layers "F.Cu" "F.Mask" "F.Paste")
			(net "M_F_CPU0_SA_DQ<1>")
		)
		(pad "10" smd rect
			(at -2.050034 -55.675022 270)
			(size 0.519938 1.4986)
			(layers "F.Cu" "F.Mask" "F.Paste")
			(net "GND")
		)
		(pad "11" smd rect
			(at -2.050034 -54.824884 270)
			(size 0.519938 1.4986)
			(layers "F.Cu" "F.Mask" "F.Paste")
			(net "M_F_CPU0_SA_DQS_DP<0>")
		)
		(pad "12" smd rect
			(at -2.050034 -53.975 270)
			(size 0.519938 1.4986)
			(layers "F.Cu" "F.Mask" "F.Paste")
			(net "M_F_CPU0_SA_DQS_DN<0>")
		)
		(pad "13" smd rect
			(at -2.050034 -53.125116 270)
			(size 0.519938 1.4986)
			(layers "F.Cu" "F.Mask" "F.Paste")
			(net "GND")
		)
		(pad "14" smd rect
			(at -2.050034 -52.274978 270)
			(size 0.519938 1.4986)
			(layers "F.Cu" "F.Mask" "F.Paste")
			(net "M_F_CPU0_SA_DQ<4>")
		)
		(pad "15" smd rect
			(at -2.050034 -51.425094 270)
			(size 0.519938 1.4986)
			(layers "F.Cu" "F.Mask" "F.Paste")
			(net "GND")
		)
		(pad "16" smd rect
			(at -2.050034 -50.574956 270)
			(size 0.519938 1.4986)
			(layers "F.Cu" "F.Mask" "F.Paste")
			(net "M_F_CPU0_SA_DQ<5>")
		)
		(pad "17" smd rect
			(at -2.050034 -49.725072 270)
			(size 0.519938 1.4986)
			(layers "F.Cu" "F.Mask" "F.Paste")
			(net "GND")
		)
		(pad "18" smd rect
			(at -2.050034 -48.874934 270)
			(size 0.519938 1.4986)
			(layers "F.Cu" "F.Mask" "F.Paste")
			(net "M_F_CPU0_SA_DQ<8>")
		)
		(pad "19" smd rect
			(at -2.050034 -48.02505 270)
			(size 0.519938 1.4986)
			(layers "F.Cu" "F.Mask" "F.Paste")
			(net "GND")
		)
		(pad "20" smd rect
			(at -2.050034 -47.174912 270)
			(size 0.519938 1.4986)
			(layers "F.Cu" "F.Mask" "F.Paste")
			(net "M_F_CPU0_SA_DQ<9>")
		)
		(pad "21" smd rect
			(at -2.050034 -46.325028 270)
			(size 0.519938 1.4986)
			(layers "F.Cu" "F.Mask" "F.Paste")
			(net "GND")
		)
		(pad "22" smd rect
			(at -2.050034 -45.47489 270)
			(size 0.519938 1.4986)
			(layers "F.Cu" "F.Mask" "F.Paste")
			(net "M_F_CPU0_SA_DQS_DP<1>")
		)
		(pad "23" smd rect
			(at -2.050034 -44.625006 270)
			(size 0.519938 1.4986)
			(layers "F.Cu" "F.Mask" "F.Paste")
			(net "M_F_CPU0_SA_DQS_DN<1>")
		)
		(pad "24" smd rect
			(at -2.050034 -43.775122 270)
			(size 0.519938 1.4986)
			(layers "F.Cu" "F.Mask" "F.Paste")
			(net "GND")
		)
		(pad "25" smd rect
			(at -2.050034 -42.924984 270)
			(size 0.519938 1.4986)
			(layers "F.Cu" "F.Mask" "F.Paste")
			(net "M_F_CPU0_SA_DQ<12>")
		)
		(pad "26" smd rect
			(at -2.050034 -42.0751 270)
			(size 0.519938 1.4986)
			(layers "F.Cu" "F.Mask" "F.Paste")
			(net "GND")
		)
		(pad "27" smd rect
			(at -2.050034 -41.224962 270)
			(size 0.519938 1.4986)
			(layers "F.Cu" "F.Mask" "F.Paste")
			(net "M_F_CPU0_SA_DQ<13>")
		)
		(pad "28" smd rect
			(at -2.050034 -40.375078 270)
			(size 0.519938 1.4986)
			(layers "F.Cu" "F.Mask" "F.Paste")
			(net "GND")
		)
		(pad "29" smd rect
			(at -2.050034 -39.52494 270)
			(size 0.519938 1.4986)
			(layers "F.Cu" "F.Mask" "F.Paste")
			(net "M_F_CPU0_SA_DQ<16>")
		)
		(pad "30" smd rect
			(at -2.050034 -38.675056 270)
			(size 0.519938 1.4986)
			(layers "F.Cu" "F.Mask" "F.Paste")
			(net "GND")
		)
		(pad "31" smd rect
			(at -2.050034 -37.824918 270)
			(size 0.519938 1.4986)
			(layers "F.Cu" "F.Mask" "F.Paste")
			(net "M_F_CPU0_SA_DQ<17>")
		)
		(pad "32" smd rect
			(at -2.050034 -36.975034 270)
			(size 0.519938 1.4986)
			(layers "F.Cu" "F.Mask" "F.Paste")
			(net "GND")
		)
		(pad "33" smd rect
			(at -2.050034 -36.124896 270)
			(size 0.519938 1.4986)
			(layers "F.Cu" "F.Mask" "F.Paste")
			(net "M_F_CPU0_SA_DQS_DP<2>")
		)
		(pad "34" smd rect
			(at -2.050034 -35.275012 270)
			(size 0.519938 1.4986)
			(layers "F.Cu" "F.Mask" "F.Paste")
			(net "M_F_CPU0_SA_DQS_DN<2>")
		)
		(pad "35" smd rect
			(at -2.050034 -34.425128 270)
			(size 0.519938 1.4986)
			(layers "F.Cu" "F.Mask" "F.Paste")
			(net "GND")
		)
		(pad "36" smd rect
			(at -2.050034 -33.57499 270)
			(size 0.519938 1.4986)
			(layers "F.Cu" "F.Mask" "F.Paste")
			(net "M_F_CPU0_SA_DQ<20>")
		)
		(pad "37" smd rect
			(at -2.050034 -32.725106 270)
			(size 0.519938 1.4986)
			(layers "F.Cu" "F.Mask" "F.Paste")
			(net "GND")
		)
		(pad "38" smd rect
			(at -2.050034 -31.874968 270)
			(size 0.519938 1.4986)
			(layers "F.Cu" "F.Mask" "F.Paste")
			(net "M_F_CPU0_SA_DQ<21>")
		)
		(pad "39" smd rect
			(at -2.050034 -31.025084 270)
			(size 0.519938 1.4986)
			(layers "F.Cu" "F.Mask" "F.Paste")
			(net "GND")
		)
		(pad "40" smd rect
			(at -2.050034 -30.174946 270)
			(size 0.519938 1.4986)
			(layers "F.Cu" "F.Mask" "F.Paste")
			(net "M_F_CPU0_SA_DQ<24>")
		)
		(pad "41" smd rect
			(at -2.050034 -29.325062 270)
			(size 0.519938 1.4986)
			(layers "F.Cu" "F.Mask" "F.Paste")
			(net "GND")
		)
		(pad "42" smd rect
			(at -2.050034 -28.474924 270)
			(size 0.519938 1.4986)
			(layers "F.Cu" "F.Mask" "F.Paste")
			(net "M_F_CPU0_SA_DQ<25>")
		)
		(pad "43" smd rect
			(at -2.050034 -27.62504 270)
			(size 0.519938 1.4986)
			(layers "F.Cu" "F.Mask" "F.Paste")
			(net "GND")
		)
		(pad "44" smd rect
			(at -2.050034 -26.774902 270)
			(size 0.519938 1.4986)
			(layers "F.Cu" "F.Mask" "F.Paste")
			(net "M_F_CPU0_SA_DQS_DP<3>")
		)
		(pad "45" smd rect
			(at -2.050034 -25.925018 270)
			(size 0.519938 1.4986)
			(layers "F.Cu" "F.Mask" "F.Paste")
			(net "M_F_CPU0_SA_DQS_DN<3>")
		)
	)
)
